# S9S_MB_2U (Grand Teton) — schematic netlist excerpt (pin names and nets, part order shuffled) for the footprints in the layout excerpt that follows; sources: Cadence DE-HDL packaged netlist, KiCad conversion of 03242023_DA0F0TMBIJ0_F0T_Motherboard_J_brd_V01_OCP.brd

R1735  Q_RES  100 1% CHIP  pkg 0402LF  page 278 : A = PVNN_TERM_CPU0 ; B = SVID_DIO1_CPU0_R
R4462  Q_RES  0 5% EMPTY  pkg 0402LF  page 196 : A = P3V3_AUX_USB_HUB_2 ; B = USB_HUB_2_DVDD

(kicad_pcb
	(version 20260206)
	(generator "pcbnew")
	(generator_version "10.0")
	(general
		(thickness 1.6)
		(legacy_teardrops no)
	)
	(paper "A4")
	(title_block
		(title "03242023_DA0F0TMBIJ0_F0T_Motherboard_J_brd_V01_OCP.brd")
		(comment 1 "Grand Teton / footprints 1540-1541 of 6105")
	)
	(layers
		(0 "F.Cu" signal "TOP")
		(4 "In1.Cu" signal "GND")
		(6 "In2.Cu" signal "IN1")
		(8 "In3.Cu" signal "GND1")
		(10 "In4.Cu" signal "IN2")
		(12 "In5.Cu" signal "GND2")
		(14 "In6.Cu" signal "IN3")
		(16 "In7.Cu" signal "GND3")
		(18 "In8.Cu" signal "VCC")
		(20 "In9.Cu" signal "VCC1")
		(22 "In10.Cu" signal "GND4")
		(24 "In11.Cu" signal "IN4")
		(26 "In12.Cu" signal "GND5")
		(28 "In13.Cu" signal "IN5")
		(30 "In14.Cu" signal "GND6")
		(32 "In15.Cu" signal "IN6")
		(34 "In16.Cu" signal "GND7")
		(2 "B.Cu" signal "BOTTOM")
		(9 "F.Adhes" user "F.Adhesive")
		(11 "B.Adhes" user "B.Adhesive")
		(13 "F.Paste" user "Package Geometry/Pastemask Top")
		(15 "B.Paste" user "Package Geometry/Pastemask Bottom")
		(5 "F.SilkS" user "Ref Des/Silkscreen Top")
		(7 "B.SilkS" user "Ref Des/Silkscreen Bottom")
		(1 "F.Mask" user "Board Geometry/Soldermask Top")
		(3 "B.Mask" user "Board Geometry/Soldermask Bottom")
		(17 "Dwgs.User" user "User.Drawings")
		(19 "Cmts.User" user "User.Comments")
		(21 "Eco1.User" user "User.Eco1")
		(23 "Eco2.User" user "User.Eco2")
		(25 "Edge.Cuts" user "Board Geometry/Outline")
		(27 "Margin" user)
		(31 "F.CrtYd" user "Package Geometry/Place Bound Top")
		(29 "B.CrtYd" user "Package Geometry/Place Bound Bottom")
		(35 "F.Fab" user "Ref Des/Assembly Top")
		(33 "B.Fab" user "Ref Des/Assembly Bottom")
	)
	(footprint ""
		(layer "F.Cu")
		(at 160.261554 -31.341568 90)
		(property "Reference" "R4462"
			(at 0 0 90)
			(layer "F.SilkS")
			(hide yes)
			(effects
				(font
					(size 1.27 1.27)
				)
			)
		)
		(property "Value" ""
			(at 0 0 90)
			(layer "F.Fab")
			(effects
				(font
					(size 1.27 1.27)
				)
			)
		)
		(duplicate_pad_numbers_are_jumpers no)
		(fp_line
			(start 0.7874 -0.4064)
			(end 0.7874 0.4064)
			(stroke
				(width 0.1524)
				(type default)
			)
			(layer "F.SilkS")
		)
		(fp_line
			(start -0.7874 -0.4064)
			(end 0.7874 -0.4064)
			(stroke
				(width 0.1524)
				(type default)
			)
			(layer "F.SilkS")
		)
		(fp_line
			(start 0.7874 0.4064)
			(end -0.7874 0.4064)
			(stroke
				(width 0.1524)
				(type default)
			)
			(layer "F.SilkS")
		)
		(fp_line
			(start -0.7874 0.4064)
			(end -0.7874 -0.4064)
			(stroke
				(width 0.1524)
				(type default)
			)
			(layer "F.SilkS")
		)
		(fp_line
			(start -0.12065 -0.305054)
			(end -0.12065 -0.2794)
			(stroke
				(width 0.1)
				(type default)
			)
			(layer "F.Fab")
		)
		(fp_line
			(start -0.67945 -0.305054)
			(end -0.12065 -0.305054)
			(stroke
				(width 0.1)
				(type default)
			)
			(layer "F.Fab")
		)
		(fp_line
			(start 0.67945 -0.3048)
			(end 0.67945 0.3048)
			(stroke
				(width 0.1)
				(type default)
			)
			(layer "F.Fab")
		)
		(fp_line
			(start 0.12065 -0.3048)
			(end 0.67945 -0.3048)
			(stroke
				(width 0.1)
				(type default)
			)
			(layer "F.Fab")
		)
		(fp_line
			(start 0.12065 -0.2794)
			(end 0.12065 -0.3048)
			(stroke
				(width 0.1)
				(type default)
			)
			(layer "F.Fab")
		)
		(fp_line
			(start -0.12065 -0.2794)
			(end 0.12065 -0.2794)
			(stroke
				(width 0.1)
				(type default)
			)
			(layer "F.Fab")
		)
		(fp_line
			(start 0.120396 0.2794)
			(end -0.12065 0.2794)
			(stroke
				(width 0.1)
				(type default)
			)
			(layer "F.Fab")
		)
		(fp_line
			(start -0.12065 0.2794)
			(end -0.12065 0.3048)
			(stroke
				(width 0.1)
				(type default)
			)
			(layer "F.Fab")
		)
		(fp_line
			(start 0.67945 0.3048)
			(end 0.120396 0.3048)
			(stroke
				(width 0.1)
				(type default)
			)
			(layer "F.Fab")
		)
		(fp_line
			(start 0.120396 0.3048)
			(end 0.120396 0.2794)
			(stroke
				(width 0.1)
				(type default)
			)
			(layer "F.Fab")
		)
		(fp_line
			(start -0.12065 0.3048)
			(end -0.67945 0.3048)
			(stroke
				(width 0.1)
				(type default)
			)
			(layer "F.Fab")
		)
		(fp_line
			(start -0.67945 0.3048)
			(end -0.67945 -0.305054)
			(stroke
				(width 0.1)
				(type default)
			)
			(layer "F.Fab")
		)
		(pad "1" smd circle
			(at -0.40005 0 90)
			(size 0 0)
			(layers "F.Cu" "F.Mask" "F.Paste")
			(net "P3V3_AUX_USB_HUB_2")
		)
		(pad "2" smd circle
			(at 0.40005 0 90)
			(size 0 0)
			(layers "F.Cu" "F.Mask" "F.Paste")
			(net "USB_HUB_2_DVDD")
		)
	)
	(footprint ""
		(layer "F.Cu")
		(at 439.262266 -124.680726 180)
		(property "Reference" "R1735"
			(at 0 0 180)
			(layer "F.SilkS")
			(hide yes)
			(effects
				(font
					(size 1.27 1.27)
				)
			)
		)
		(property "Value" ""
			(at 0 0 180)
			(layer "F.Fab")
			(effects
				(font
					(size 1.27 1.27)
				)
			)
		)
		(duplicate_pad_numbers_are_jumpers no)
		(fp_line
			(start 0.7874 0.4064)
			(end -0.7874 0.4064)
			(stroke
				(width 0.1524)
				(type default)
			)
			(layer "F.SilkS")
		)
		(fp_line
			(start 0.7874 -0.4064)
			(end 0.7874 0.4064)
			(stroke
				(width 0.1524)
				(type default)
			)
			(layer "F.SilkS")
		)
		(fp_line
			(start -0.7874 0.4064)
			(end -0.7874 -0.4064)
			(stroke
				(width 0.1524)
				(type default)
			)
			(layer "F.SilkS")
		)
		(fp_line
			(start -0.7874 -0.4064)
			(end 0.7874 -0.4064)
			(stroke
				(width 0.1524)
				(type default)
			)
			(layer "F.SilkS")
		)
		(fp_line
			(start 0.67945 0.3048)
			(end 0.120396 0.3048)
			(stroke
				(width 0.1)
				(type default)
			)
			(layer "F.Fab")
		)
		(fp_line
			(start 0.67945 -0.3048)
			(end 0.67945 0.3048)
			(stroke
				(width 0.1)
				(type default)
			)
			(layer "F.Fab")
		)
		(fp_line
			(start 0.12065 -0.2794)
			(end 0.12065 -0.3048)
			(stroke
				(width 0.1)
				(type default)
			)
			(layer "F.Fab")
		)
		(fp_line
			(start 0.12065 -0.3048)
			(end 0.67945 -0.3048)
			(stroke
				(width 0.1)
				(type default)
			)
			(layer "F.Fab")
		)
		(fp_line
			(start 0.120396 0.3048)
			(end 0.120396 0.2794)
			(stroke
				(width 0.1)
				(type default)
			)
			(layer "F.Fab")
		)
		(fp_line
			(start 0.120396 0.2794)
			(end -0.12065 0.2794)
			(stroke
				(width 0.1)
				(type default)
			)
			(layer "F.Fab")
		)
		(fp_line
			(start -0.12065 0.3048)
			(end -0.67945 0.3048)
			(stroke
				(width 0.1)
				(type default)
			)
			(layer "F.Fab")
		)
		(fp_line
			(start -0.12065 0.2794)
			(end -0.12065 0.3048)
			(stroke
				(width 0.1)
				(type default)
			)
			(layer "F.Fab")
		)
		(fp_line
			(start -0.12065 -0.2794)
			(end 0.12065 -0.2794)
			(stroke
				(width 0.1)
				(type default)
			)
			(layer "F.Fab")
		)
		(fp_line
			(start -0.12065 -0.305054)
			(end -0.12065 -0.2794)
			(stroke
				(width 0.1)
				(type default)
			)
			(layer "F.Fab")
		)
		(fp_line
			(start -0.67945 0.3048)
			(end -0.67945 -0.305054)
			(stroke
				(width 0.1)
				(type default)
			)
			(layer "F.Fab")
		)
		(fp_line
			(start -0.67945 -0.305054)
			(end -0.12065 -0.305054)
			(stroke
				(width 0.1)
				(type default)
			)
			(layer "F.Fab")
		)
		(pad "1" smd circle
			(at -0.40005 0 180)
			(size 0 0)
			(layers "F.Cu" "F.Mask" "F.Paste")
			(net "PVNN_TERM_CPU0")
		)
		(pad "2" smd circle
			(at 0.40005 0 180)
			(size 0 0)
			(layers "F.Cu" "F.Mask" "F.Paste")
			(net "SVID_DIO1_CPU0_R")
		)
	)
)
